(kicad_pcb
	(version 20260206)
	(generator "pcbnew")
	(generator_version "10.0")
	(general
		(thickness 1.6)
		(legacy_teardrops no)
	)
	(paper "A4")
	(title_block
		(title "01162023_DA0F0TEBIF0_F0T_Expander_BD_F_brd_V02_OCP.brd")
		(comment 1 "Grand Teton / footprints 2506-2513 of 9728")
	)
	(layers
		(0 "F.Cu" signal "TOP")
		(4 "In1.Cu" signal "GND")
		(6 "In2.Cu" signal "VCC")
		(8 "In3.Cu" signal "VCC1")
		(10 "In4.Cu" signal "GND1")
		(12 "In5.Cu" signal "IN1")
		(14 "In6.Cu" signal "GND2")
		(16 "In7.Cu" signal "IN2")
		(18 "In8.Cu" signal "GND3")
		(20 "In9.Cu" signal "IN3")
		(22 "In10.Cu" signal "GND4")
		(24 "In11.Cu" signal "IN4")
		(26 "In12.Cu" signal "GND5")
		(28 "In13.Cu" signal "IN5")
		(30 "In14.Cu" signal "GND6")
		(32 "In15.Cu" signal "IN6")
		(34 "In16.Cu" signal "GND7")
		(2 "B.Cu" signal "BOTTOM")
		(9 "F.Adhes" user "F.Adhesive")
		(11 "B.Adhes" user "B.Adhesive")
		(13 "F.Paste" user "Package Geometry/Pastemask Top")
		(15 "B.Paste" user "Package Geometry/Pastemask Bottom")
		(5 "F.SilkS" user "Ref Des/Silkscreen Top")
		(7 "B.SilkS" user "Ref Des/Silkscreen Bottom")
		(1 "F.Mask" user "Board Geometry/Soldermask Top")
		(3 "B.Mask" user "Board Geometry/Soldermask Bottom")
		(17 "Dwgs.User" user "User.Drawings")
		(19 "Cmts.User" user "User.Comments")
		(21 "Eco1.User" user "User.Eco1")
		(23 "Eco2.User" user "User.Eco2")
		(25 "Edge.Cuts" user "Board Geometry/Outline")
		(27 "Margin" user)
		(31 "F.CrtYd" user "Package Geometry/Place Bound Top")
		(29 "B.CrtYd" user "Package Geometry/Place Bound Bottom")
		(35 "F.Fab" user "Ref Des/Assembly Top")
		(33 "B.Fab" user "Ref Des/Assembly Bottom")
	)
	(footprint ""
		(layer "F.Cu")
		(at 121.13514 -98.320606)
		(property "Reference" "R1558"
			(at 0 0 0)
			(layer "F.SilkS")
			(hide yes)
			(effects
				(font
					(size 1.27 1.27)
				)
			)
		)
		(property "Value" ""
			(at 0 0 0)
			(layer "F.Fab")
			(effects
				(font
					(size 1.27 1.27)
				)
			)
		)
		(duplicate_pad_numbers_are_jumpers no)
		(fp_line
			(start -0.7874 -0.4064)
			(end 0.7874 -0.4064)
			(stroke
				(width 0.1524)
				(type default)
			)
			(layer "F.SilkS")
		)
		(fp_line
			(start -0.7874 0.4064)
			(end -0.7874 -0.4064)
			(stroke
				(width 0.1524)
				(type default)
			)
			(layer "F.SilkS")
		)
		(fp_line
			(start 0.7874 -0.4064)
			(end 0.7874 0.4064)
			(stroke
				(width 0.1524)
				(type default)
			)
			(layer "F.SilkS")
		)
		(fp_line
			(start 0.7874 0.4064)
			(end -0.7874 0.4064)
			(stroke
				(width 0.1524)
				(type default)
			)
			(layer "F.SilkS")
		)
		(fp_line
			(start -0.67945 -0.305054)
			(end -0.12065 -0.305054)
			(stroke
				(width 0.1)
				(type default)
			)
			(layer "F.Fab")
		)
		(fp_line
			(start -0.67945 0.3048)
			(end -0.67945 -0.305054)
			(stroke
				(width 0.1)
				(type default)
			)
			(layer "F.Fab")
		)
		(fp_line
			(start -0.12065 -0.305054)
			(end -0.12065 -0.2794)
			(stroke
				(width 0.1)
				(type default)
			)
			(layer "F.Fab")
		)
		(fp_line
			(start -0.12065 -0.2794)
			(end 0.12065 -0.2794)
			(stroke
				(width 0.1)
				(type default)
			)
			(layer "F.Fab")
		)
		(fp_line
			(start -0.12065 0.2794)
			(end -0.12065 0.3048)
			(stroke
				(width 0.1)
				(type default)
			)
			(layer "F.Fab")
		)
		(fp_line
			(start -0.12065 0.3048)
			(end -0.67945 0.3048)
			(stroke
				(width 0.1)
				(type default)
			)
			(layer "F.Fab")
		)
		(fp_line
			(start 0.120396 0.2794)
			(end -0.12065 0.2794)
			(stroke
				(width 0.1)
				(type default)
			)
			(layer "F.Fab")
		)
		(fp_line
			(start 0.120396 0.3048)
			(end 0.120396 0.2794)
			(stroke
				(width 0.1)
				(type default)
			)
			(layer "F.Fab")
		)
		(fp_line
			(start 0.12065 -0.3048)
			(end 0.67945 -0.3048)
			(stroke
				(width 0.1)
				(type default)
			)
			(layer "F.Fab")
		)
		(fp_line
			(start 0.12065 -0.2794)
			(end 0.12065 -0.3048)
			(stroke
				(width 0.1)
				(type default)
			)
			(layer "F.Fab")
		)
		(fp_line
			(start 0.67945 -0.3048)
			(end 0.67945 0.3048)
			(stroke
				(width 0.1)
				(type default)
			)
			(layer "F.Fab")
		)
		(fp_line
			(start 0.67945 0.3048)
			(end 0.120396 0.3048)
			(stroke
				(width 0.1)
				(type default)
			)
			(layer "F.Fab")
		)
		(pad "1" smd circle
			(at -0.40005 0)
			(size 0 0)
			(layers "F.Cu" "F.Mask" "F.Paste")
			(net "P3V3_AUX")
		)
		(pad "2" smd circle
			(at 0.40005 0)
			(size 0 0)
			(layers "F.Cu" "F.Mask" "F.Paste")
			(net "BIC_I2C9_SSD_MUX0_A1")
		)
	)
	(footprint ""
		(layer "F.Cu")
		(at 27.390344 -252.356874 -90)
		(property "Reference" "R1196"
			(at 0 0 270)
			(layer "F.SilkS")
			(hide yes)
			(effects
				(font
					(size 1.27 1.27)
				)
			)
		)
		(property "Value" ""
			(at 0 0 270)
			(layer "F.Fab")
			(effects
				(font
					(size 1.27 1.27)
				)
			)
		)
		(duplicate_pad_numbers_are_jumpers no)
		(fp_line
			(start -0.7874 0.4064)
			(end -0.7874 -0.4064)
			(stroke
				(width 0.1524)
				(type default)
			)
			(layer "F.SilkS")
		)
		(fp_line
			(start 0.7874 0.4064)
			(end -0.7874 0.4064)
			(stroke
				(width 0.1524)
				(type default)
			)
			(layer "F.SilkS")
		)
		(fp_line
			(start -0.7874 -0.4064)
			(end 0.7874 -0.4064)
			(stroke
				(width 0.1524)
				(type default)
			)
			(layer "F.SilkS")
		)
		(fp_line
			(start 0.7874 -0.4064)
			(end 0.7874 0.4064)
			(stroke
				(width 0.1524)
				(type default)
			)
			(layer "F.SilkS")
		)
		(fp_line
			(start -0.67945 0.3048)
			(end -0.67945 -0.305054)
			(stroke
				(width 0.1)
				(type default)
			)
			(layer "F.Fab")
		)
		(fp_line
			(start -0.12065 0.3048)
			(end -0.67945 0.3048)
			(stroke
				(width 0.1)
				(type default)
			)
			(layer "F.Fab")
		)
		(fp_line
			(start 0.120396 0.3048)
			(end 0.120396 0.2794)
			(stroke
				(width 0.1)
				(type default)
			)
			(layer "F.Fab")
		)
		(fp_line
			(start 0.67945 0.3048)
			(end 0.120396 0.3048)
			(stroke
				(width 0.1)
				(type default)
			)
			(layer "F.Fab")
		)
		(fp_line
			(start -0.12065 0.2794)
			(end -0.12065 0.3048)
			(stroke
				(width 0.1)
				(type default)
			)
			(layer "F.Fab")
		)
		(fp_line
			(start 0.120396 0.2794)
			(end -0.12065 0.2794)
			(stroke
				(width 0.1)
				(type default)
			)
			(layer "F.Fab")
		)
		(fp_line
			(start -0.12065 -0.2794)
			(end 0.12065 -0.2794)
			(stroke
				(width 0.1)
				(type default)
			)
			(layer "F.Fab")
		)
		(fp_line
			(start 0.12065 -0.2794)
			(end 0.12065 -0.3048)
			(stroke
				(width 0.1)
				(type default)
			)
			(layer "F.Fab")
		)
		(fp_line
			(start 0.12065 -0.3048)
			(end 0.67945 -0.3048)
			(stroke
				(width 0.1)
				(type default)
			)
			(layer "F.Fab")
		)
		(fp_line
			(start 0.67945 -0.3048)
			(end 0.67945 0.3048)
			(stroke
				(width 0.1)
				(type default)
			)
			(layer "F.Fab")
		)
		(fp_line
			(start -0.67945 -0.305054)
			(end -0.12065 -0.305054)
			(stroke
				(width 0.1)
				(type default)
			)
			(layer "F.Fab")
		)
		(fp_line
			(start -0.12065 -0.305054)
			(end -0.12065 -0.2794)
			(stroke
				(width 0.1)
				(type default)
			)
			(layer "F.Fab")
		)
		(pad "1" smd circle
			(at -0.40005 0 270)
			(size 0 0)
			(layers "F.Cu" "F.Mask" "F.Paste")
			(net "GND")
		)
		(pad "2" smd circle
			(at 0.40005 0 270)
			(size 0 0)
			(layers "F.Cu" "F.Mask" "F.Paste")
			(net "PEX0_MODE_SEL5")
		)
	)
	(footprint ""
		(layer "F.Cu")
		(at 4.647692 -24.934164 -90)
		(property "Reference" "R1633"
			(at 0 0 270)
			(layer "F.SilkS")
			(hide yes)
			(effects
				(font
					(size 1.27 1.27)
				)
			)
		)
		(property "Value" ""
			(at 0 0 270)
			(layer "F.Fab")
			(effects
				(font
					(size 1.27 1.27)
				)
			)
		)
		(duplicate_pad_numbers_are_jumpers no)
		(fp_line
			(start -0.7874 0.4064)
			(end -0.7874 -0.4064)
			(stroke
				(width 0.1524)
				(type default)
			)
			(layer "F.SilkS")
		)
		(fp_line
			(start 0.7874 0.4064)
			(end -0.7874 0.4064)
			(stroke
				(width 0.1524)
				(type default)
			)
			(layer "F.SilkS")
		)
		(fp_line
			(start -0.7874 -0.4064)
			(end 0.7874 -0.4064)
			(stroke
				(width 0.1524)
				(type default)
			)
			(layer "F.SilkS")
		)
		(fp_line
			(start 0.7874 -0.4064)
			(end 0.7874 0.4064)
			(stroke
				(width 0.1524)
				(type default)
			)
			(layer "F.SilkS")
		)
		(fp_line
			(start -0.67945 0.3048)
			(end -0.67945 -0.305054)
			(stroke
				(width 0.1)
				(type default)
			)
			(layer "F.Fab")
		)
		(fp_line
			(start -0.12065 0.3048)
			(end -0.67945 0.3048)
			(stroke
				(width 0.1)
				(type default)
			)
			(layer "F.Fab")
		)
		(fp_line
			(start 0.120396 0.3048)
			(end 0.120396 0.2794)
			(stroke
				(width 0.1)
				(type default)
			)
			(layer "F.Fab")
		)
		(fp_line
			(start 0.67945 0.3048)
			(end 0.120396 0.3048)
			(stroke
				(width 0.1)
				(type default)
			)
			(layer "F.Fab")
		)
		(fp_line
			(start -0.12065 0.2794)
			(end -0.12065 0.3048)
			(stroke
				(width 0.1)
				(type default)
			)
			(layer "F.Fab")
		)
		(fp_line
			(start 0.120396 0.2794)
			(end -0.12065 0.2794)
			(stroke
				(width 0.1)
				(type default)
			)
			(layer "F.Fab")
		)
		(fp_line
			(start -0.12065 -0.2794)
			(end 0.12065 -0.2794)
			(stroke
				(width 0.1)
				(type default)
			)
			(layer "F.Fab")
		)
		(fp_line
			(start 0.12065 -0.2794)
			(end 0.12065 -0.3048)
			(stroke
				(width 0.1)
				(type default)
			)
			(layer "F.Fab")
		)
		(fp_line
			(start 0.12065 -0.3048)
			(end 0.67945 -0.3048)
			(stroke
				(width 0.1)
				(type default)
			)
			(layer "F.Fab")
		)
		(fp_line
			(start 0.67945 -0.3048)
			(end 0.67945 0.3048)
			(stroke
				(width 0.1)
				(type default)
			)
			(layer "F.Fab")
		)
		(fp_line
			(start -0.67945 -0.305054)
			(end -0.12065 -0.305054)
			(stroke
				(width 0.1)
				(type default)
			)
			(layer "F.Fab")
		)
		(fp_line
			(start -0.12065 -0.305054)
			(end -0.12065 -0.2794)
			(stroke
				(width 0.1)
				(type default)
			)
			(layer "F.Fab")
		)
		(pad "1" smd circle
			(at -0.40005 0 270)
			(size 0 0)
			(layers "F.Cu" "F.Mask" "F.Paste")
			(net "P3V3_SSD0")
		)
		(pad "2" smd circle
			(at 0.40005 0 270)
			(size 0 0)
			(layers "F.Cu" "F.Mask" "F.Paste")
			(net "SMB_ISO_SSD0_SDA")
		)
	)
	(footprint ""
		(layer "F.Cu")
		(at 155.380436 -102.888796)
		(property "Reference" "C270"
			(at 0 0 0)
			(layer "F.SilkS")
			(hide yes)
			(effects
				(font
					(size 1.27 1.27)
				)
			)
		)
		(property "Value" ""
			(at 0 0 0)
			(layer "F.Fab")
			(effects
				(font
					(size 1.27 1.27)
				)
			)
		)
		(duplicate_pad_numbers_are_jumpers no)
		(fp_line
			(start -0.299974 -0.150114)
			(end 0.299974 -0.150114)
			(stroke
				(width 0.1)
				(type default)
			)
			(layer "F.Fab")
		)
		(fp_line
			(start -0.299974 0.150114)
			(end -0.299974 -0.150114)
			(stroke
				(width 0.1)
				(type default)
			)
			(layer "F.Fab")
		)
		(fp_line
			(start 0.299974 -0.150114)
			(end 0.299974 0.150114)
			(stroke
				(width 0.1)
				(type default)
			)
			(layer "F.Fab")
		)
		(fp_line
			(start 0.299974 0.150114)
			(end -0.299974 0.150114)
			(stroke
				(width 0.1)
				(type default)
			)
			(layer "F.Fab")
		)
		(pad "1" smd rect
			(at -0.2667 0)
			(size 0.3048 0.381)
			(layers "F.Cu" "F.Mask" "F.Paste")
			(net "P5E_PEX1_STN1_TX_DP<18>")
		)
		(pad "2" smd rect
			(at 0.2667 0)
			(size 0.3048 0.381)
			(layers "F.Cu" "F.Mask" "F.Paste")
			(net "P5E_PEX1_STN1_TX_C_DP<18>")
		)
	)
	(footprint ""
		(layer "F.Cu")
		(at 44.619926 -15.649956 180)
		(property "Reference" "H100"
			(at -0.987298 2.69621 0)
			(unlocked yes)
			(layer "B.SilkS")
			(effects
				(font
					(size 0.7874 0.5842)
					(thickness 0.1524)
				)
				(justify left mirror)
			)
		)
		(property "Value" ""
			(at 0 0 180)
			(layer "F.Fab")
			(effects
				(font
					(size 1.27 1.27)
				)
			)
		)
		(duplicate_pad_numbers_are_jumpers no)
		(pad "1" thru_hole rect
			(at 0 0 180)
			(size 4.2164 5.0038)
			(drill 2.0066
				(offset 0.099822 0)
			)
			(layers "*.Cu" "*.Mask")
			(remove_unused_layers no)
			(net "Net_8563")
			(clearance -0.8509)
			(padstack
				(mode front_inner_back)
				(layer "Inner"
					(shape circle)
					(size 4.0132 4.0132)
					(clearance -0.7493)
				)
				(layer "B.Cu"
					(shape circle)
					(size 4.0132 4.0132)
					(clearance -0.7493)
				)
			)
		)
	)
	(footprint ""
		(layer "F.Cu")
		(at 15.926562 -121.408952 180)
		(property "Reference" "PC451"
			(at 0 0 180)
			(layer "F.SilkS")
			(hide yes)
			(effects
				(font
					(size 1.27 1.27)
				)
			)
		)
		(property "Value" ""
			(at 0 0 180)
			(layer "F.Fab")
			(effects
				(font
					(size 1.27 1.27)
				)
			)
		)
		(duplicate_pad_numbers_are_jumpers no)
		(fp_line
			(start 1.524 0.762)
			(end -1.524 0.762)
			(stroke
				(width 0.1524)
				(type default)
			)
			(layer "F.SilkS")
		)
		(fp_line
			(start 1.524 -0.762)
			(end 1.524 0.762)
			(stroke
				(width 0.1524)
				(type default)
			)
			(layer "F.SilkS")
		)
		(fp_line
			(start -1.524 0.762)
			(end -1.524 -0.762)
			(stroke
				(width 0.1524)
				(type default)
			)
			(layer "F.SilkS")
		)
		(fp_line
			(start -1.524 -0.762)
			(end 1.524 -0.762)
			(stroke
				(width 0.1524)
				(type default)
			)
			(layer "F.SilkS")
		)
		(fp_line
			(start 1.1049 0.724916)
			(end 1.1049 -0.724916)
			(stroke
				(width 0.1)
				(type default)
			)
			(layer "F.Fab")
		)
		(fp_line
			(start 1.1049 -0.724916)
			(end -1.1049 -0.724916)
			(stroke
				(width 0.1)
				(type default)
			)
			(layer "F.Fab")
		)
		(fp_line
			(start -1.1049 0.724916)
			(end 1.1049 0.724916)
			(stroke
				(width 0.1)
				(type default)
			)
			(layer "F.Fab")
		)
		(fp_line
			(start -1.1049 -0.724916)
			(end -1.1049 0.724916)
			(stroke
				(width 0.1)
				(type default)
			)
			(layer "F.Fab")
		)
		(pad "1" smd rect
			(at -0.889 0)
			(size 1.016 1.27)
			(layers "F.Cu" "F.Mask" "F.Paste")
			(net "GND")
		)
		(pad "2" smd rect
			(at 0.889 0)
			(size 1.016 1.27)
			(layers "F.Cu" "F.Mask" "F.Paste")
			(net "P3V3_AUX")
		)
	)
	(footprint ""
		(layer "F.Cu")
		(at 228.22789 -35.876738)
		(property "Reference" "R6082"
			(at 0 0 0)
			(layer "F.SilkS")
			(hide yes)
			(effects
				(font
					(size 1.27 1.27)
				)
			)
		)
		(property "Value" ""
			(at 0 0 0)
			(layer "F.Fab")
			(effects
				(font
					(size 1.27 1.27)
				)
			)
		)
		(duplicate_pad_numbers_are_jumpers no)
		(fp_line
			(start -0.7874 -0.4064)
			(end 0.7874 -0.4064)
			(stroke
				(width 0.1524)
				(type default)
			)
			(layer "F.SilkS")
		)
		(fp_line
			(start -0.7874 0.4064)
			(end -0.7874 -0.4064)
			(stroke
				(width 0.1524)
				(type default)
			)
			(layer "F.SilkS")
		)
		(fp_line
			(start 0.7874 -0.4064)
			(end 0.7874 0.4064)
			(stroke
				(width 0.1524)
				(type default)
			)
			(layer "F.SilkS")
		)
		(fp_line
			(start 0.7874 0.4064)
			(end -0.7874 0.4064)
			(stroke
				(width 0.1524)
				(type default)
			)
			(layer "F.SilkS")
		)
		(fp_line
			(start -0.67945 -0.305054)
			(end -0.12065 -0.305054)
			(stroke
				(width 0.1)
				(type default)
			)
			(layer "F.Fab")
		)
		(fp_line
			(start -0.67945 0.3048)
			(end -0.67945 -0.305054)
			(stroke
				(width 0.1)
				(type default)
			)
			(layer "F.Fab")
		)
		(fp_line
			(start -0.12065 -0.305054)
			(end -0.12065 -0.2794)
			(stroke
				(width 0.1)
				(type default)
			)
			(layer "F.Fab")
		)
		(fp_line
			(start -0.12065 -0.2794)
			(end 0.12065 -0.2794)
			(stroke
				(width 0.1)
				(type default)
			)
			(layer "F.Fab")
		)
		(fp_line
			(start -0.12065 0.2794)
			(end -0.12065 0.3048)
			(stroke
				(width 0.1)
				(type default)
			)
			(layer "F.Fab")
		)
		(fp_line
			(start -0.12065 0.3048)
			(end -0.67945 0.3048)
			(stroke
				(width 0.1)
				(type default)
			)
			(layer "F.Fab")
		)
		(fp_line
			(start 0.120396 0.2794)
			(end -0.12065 0.2794)
			(stroke
				(width 0.1)
				(type default)
			)
			(layer "F.Fab")
		)
		(fp_line
			(start 0.120396 0.3048)
			(end 0.120396 0.2794)
			(stroke
				(width 0.1)
				(type default)
			)
			(layer "F.Fab")
		)
		(fp_line
			(start 0.12065 -0.3048)
			(end 0.67945 -0.3048)
			(stroke
				(width 0.1)
				(type default)
			)
			(layer "F.Fab")
		)
		(fp_line
			(start 0.12065 -0.2794)
			(end 0.12065 -0.3048)
			(stroke
				(width 0.1)
				(type default)
			)
			(layer "F.Fab")
		)
		(fp_line
			(start 0.67945 -0.3048)
			(end 0.67945 0.3048)
			(stroke
				(width 0.1)
				(type default)
			)
			(layer "F.Fab")
		)
		(fp_line
			(start 0.67945 0.3048)
			(end 0.120396 0.3048)
			(stroke
				(width 0.1)
				(type default)
			)
			(layer "F.Fab")
		)
		(pad "1" smd circle
			(at -0.40005 0)
			(size 0 0)
			(layers "F.Cu" "F.Mask" "F.Paste")
			(net "PWRGD_P3V3_SSD8_D")
		)
		(pad "2" smd circle
			(at 0.40005 0)
			(size 0 0)
			(layers "F.Cu" "F.Mask" "F.Paste")
			(net "PWRGD_P3V3_SSD8_R")
		)
	)
	(footprint ""
		(layer "F.Cu")
		(at 133.892544 -28.225242 180)
		(property "Reference" "C283"
			(at 0 0 180)
			(layer "F.SilkS")
			(hide yes)
			(effects
				(font
					(size 1.27 1.27)
				)
			)
		)
		(property "Value" ""
			(at 0 0 180)
			(layer "F.Fab")
			(effects
				(font
					(size 1.27 1.27)
				)
			)
		)
		(duplicate_pad_numbers_are_jumpers no)
		(fp_line
			(start 0.299974 0.150114)
			(end -0.299974 0.150114)
			(stroke
				(width 0.1)
				(type default)
			)
			(layer "F.Fab")
		)
		(fp_line
			(start 0.299974 -0.150114)
			(end 0.299974 0.150114)
			(stroke
				(width 0.1)
				(type default)
			)
			(layer "F.Fab")
		)
		(fp_line
			(start -0.299974 0.150114)
			(end -0.299974 -0.150114)
			(stroke
				(width 0.1)
				(type default)
			)
			(layer "F.Fab")
		)
		(fp_line
			(start -0.299974 -0.150114)
			(end 0.299974 -0.150114)
			(stroke
				(width 0.1)
				(type default)
			)
			(layer "F.Fab")
		)
		(pad "1" smd rect
			(at -0.2667 0 180)
			(size 0.3048 0.381)
			(layers "F.Cu" "F.Mask" "F.Paste")
			(net "P5E_PEX1_STN2_TX_DN<44>")
		)
		(pad "2" smd rect
			(at 0.2667 0 180)
			(size 0.3048 0.381)
			(layers "F.Cu" "F.Mask" "F.Paste")
			(net "P5E_PEX1_STN2_TX_C_DN<44>")
		)
	)
)
